# BASEBOARD_FAB2 (Tioga Pass) — schematic netlist excerpt (pin names and nets, part order shuffled) for the footprints in the layout excerpt that follows; sources: Cadence DE-HDL packaged netlist, KiCad conversion of Wiwynn_Tioga_Pass_MB.brd

C2T36  CAP_A  0.1UF 16V 10% X7R  pkg 0402V  page 198 : A = P3V3_STBY ; B = GND
C5G98  CAP_A  22.0UF 4V 20% X6S  pkg 0603V  page 243 : A = PVDDQ_KLM ; B = GND
C8T3  CAP  100UF 4V 20% X5R  pkg 0805  page 229 : A = PVTT_GHJ ; B = GND

(kicad_pcb
	(version 20260206)
	(generator "pcbnew")
	(generator_version "10.0")
	(general
		(thickness 1.6)
		(legacy_teardrops no)
	)
	(paper "A4")
	(title_block
		(title "Wiwynn_Tioga_Pass_MB.brd")
		(comment 1 "Tioga Pass / footprints 3727-3729 of 4770")
	)
	(layers
		(0 "F.Cu" signal "TOP")
		(4 "In1.Cu" signal "L2GND")
		(6 "In2.Cu" signal "L3")
		(8 "In3.Cu" signal "L4GND")
		(10 "In4.Cu" signal "L5")
		(12 "In5.Cu" signal "L6GND")
		(14 "In6.Cu" signal "L7VCC")
		(16 "In7.Cu" signal "L8VCC")
		(18 "In8.Cu" signal "L9GND")
		(20 "In9.Cu" signal "L10")
		(22 "In10.Cu" signal "L11GND")
		(24 "In11.Cu" signal "L12")
		(26 "In12.Cu" signal "L13GND")
		(2 "B.Cu" signal "BOTTOM")
		(9 "F.Adhes" user "F.Adhesive")
		(11 "B.Adhes" user "B.Adhesive")
		(13 "F.Paste" user "Package Geometry/Pastemask Top")
		(15 "B.Paste" user "Package Geometry/Pastemask Bottom")
		(5 "F.SilkS" user "Ref Des/Silkscreen Top")
		(7 "B.SilkS" user "Ref Des/Silkscreen Bottom")
		(1 "F.Mask" user "Board Geometry/Soldermask Top")
		(3 "B.Mask" user "Board Geometry/Soldermask Bottom")
		(17 "Dwgs.User" user "User.Drawings")
		(19 "Cmts.User" user "User.Comments")
		(21 "Eco1.User" user "User.Eco1")
		(23 "Eco2.User" user "User.Eco2")
		(25 "Edge.Cuts" user "Board Geometry/Outline")
		(27 "Margin" user)
		(31 "F.CrtYd" user "Package Geometry/Place Bound Top")
		(29 "B.CrtYd" user "Package Geometry/Place Bound Bottom")
		(35 "F.Fab" user "Ref Des/Assembly Top")
		(33 "B.Fab" user "Ref Des/Assembly Bottom")
	)
	(footprint ""
		(layer "B.Cu")
		(at 88.392 -149.8092 90)
		(property "Reference" "C5G98"
			(at -1.14681 0.76708 180)
			(unlocked yes)
			(layer "B.SilkS")
			(effects
				(font
					(size 0.7874 0.5842)
					(thickness 0.1524)
				)
				(justify mirror)
			)
		)
		(property "Value" ""
			(at 0 0 90)
			(layer "B.Fab")
			(effects
				(font
					(size 1.27 1.27)
				)
				(justify mirror)
			)
		)
		(duplicate_pad_numbers_are_jumpers no)
		(fp_rect
			(start -0.4953 -0.2032)
			(end 0.4953 1.6002)
			(stroke
				(width 0)
				(type default)
			)
			(fill no)
			(layer "B.CrtYd")
		)
		(fp_line
			(start 0.4953 -0.2032)
			(end -0.4953 -0.2032)
			(stroke
				(width 0.1)
				(type default)
			)
			(layer "B.Fab")
		)
		(fp_line
			(start -0.4953 -0.2032)
			(end -0.4953 1.6002)
			(stroke
				(width 0.1)
				(type default)
			)
			(layer "B.Fab")
		)
		(fp_line
			(start 0.4953 1.6002)
			(end 0.4953 -0.2032)
			(stroke
				(width 0.1)
				(type default)
			)
			(layer "B.Fab")
		)
		(fp_line
			(start -0.4953 1.6002)
			(end 0.4953 1.6002)
			(stroke
				(width 0.1)
				(type default)
			)
			(layer "B.Fab")
		)
		(pad "1" smd rect
			(at 0 0 270)
			(size 0.762 0.889)
			(layers "B.Cu" "B.Mask" "B.Paste")
			(net "PVDDQ_KLM")
		)
		(pad "2" smd rect
			(at 0 1.397 270)
			(size 0.762 0.889)
			(layers "B.Cu" "B.Mask" "B.Paste")
			(net "GND")
		)
		(zone
			(layer "B.Cu")
			(hatch none 0.5)
			(connect_pads
				(clearance 0)
			)
			(min_thickness 0.25)
			(keepout
				(tracks not_allowed)
				(vias allowed)
				(pads allowed)
				(copperpour not_allowed)
				(footprints allowed)
			)
			(placement
				(enabled no)
				(sheetname "")
			)
			(fill
				(thermal_gap 0.5)
				(thermal_bridge_width 0.5)
				(island_removal_mode 0)
			)
			(polygon
				(pts
					(xy 88.8365 -149.4282) (xy 89.3445 -149.4282) (xy 89.3445 -150.1902) (xy 88.8365 -150.1902)
				)
			)
		)
	)
	(footprint ""
		(layer "B.Cu")
		(at 95.374968 -27.051 90)
		(property "Reference" "C8T3"
			(at -1.47828 0.78994 180)
			(unlocked yes)
			(layer "B.SilkS")
			(effects
				(font
					(size 0.4064 0.254)
					(thickness 0.1524)
				)
				(justify mirror)
			)
		)
		(property "Value" ""
			(at 0 0 90)
			(layer "B.Fab")
			(effects
				(font
					(size 1.27 1.27)
				)
				(justify mirror)
			)
		)
		(duplicate_pad_numbers_are_jumpers no)
		(fp_poly
			(pts
				(xy 0.7239 -0.2159) (xy -0.7239 -0.2159) (xy -0.7239 1.9939) (xy 0.7239 1.9939)
			)
			(stroke
				(width 0)
				(type default)
			)
			(fill no)
			(layer "B.CrtYd")
		)
		(fp_line
			(start 0.7239 -0.2159)
			(end 0.7239 1.9939)
			(stroke
				(width 0.1)
				(type default)
			)
			(layer "B.Fab")
		)
		(fp_line
			(start -0.7239 -0.2159)
			(end 0.7239 -0.2159)
			(stroke
				(width 0.1)
				(type default)
			)
			(layer "B.Fab")
		)
		(fp_line
			(start 0.7239 1.9939)
			(end -0.7239 1.9939)
			(stroke
				(width 0.1)
				(type default)
			)
			(layer "B.Fab")
		)
		(fp_line
			(start -0.7239 1.9939)
			(end -0.7239 -0.2159)
			(stroke
				(width 0.1)
				(type default)
			)
			(layer "B.Fab")
		)
		(pad "1" smd rect
			(at 0 0 270)
			(size 1.27 1.016)
			(layers "B.Cu" "B.Mask" "B.Paste")
			(net "PVTT_GHJ")
		)
		(pad "2" smd rect
			(at 0 1.778 270)
			(size 1.27 1.016)
			(layers "B.Cu" "B.Mask" "B.Paste")
			(net "GND")
		)
		(zone
			(layer "B.Cu")
			(hatch none 0.5)
			(connect_pads
				(clearance 0)
			)
			(min_thickness 0.25)
			(keepout
				(tracks not_allowed)
				(vias allowed)
				(pads allowed)
				(copperpour not_allowed)
				(footprints allowed)
			)
			(placement
				(enabled no)
				(sheetname "")
			)
			(fill
				(thermal_gap 0.5)
				(thermal_bridge_width 0.5)
				(island_removal_mode 0)
			)
			(polygon
				(pts
					(xy 95.882968 -27.686) (xy 95.882968 -26.416) (xy 96.644968 -26.416) (xy 96.644968 -27.686)
				)
			)
		)
	)
	(footprint ""
		(layer "B.Cu")
		(at 462.949544 -10.69848 -90)
		(property "Reference" "C2T36"
			(at 0 0 90)
			(layer "B.SilkS")
			(hide yes)
			(effects
				(font
					(size 1.27 1.27)
				)
				(justify mirror)
			)
		)
		(property "Value" ""
			(at 0 0 90)
			(layer "B.Fab")
			(effects
				(font
					(size 1.27 1.27)
				)
				(justify mirror)
			)
		)
		(duplicate_pad_numbers_are_jumpers no)
		(fp_rect
			(start -0.3048 0.9906)
			(end 0.3048 -0.1016)
			(stroke
				(width 0)
				(type default)
			)
			(fill no)
			(layer "B.CrtYd")
		)
		(fp_line
			(start -0.3048 0.9906)
			(end -0.3048 -0.1016)
			(stroke
				(width 0.1)
				(type default)
			)
			(layer "B.Fab")
		)
		(fp_line
			(start 0.3048 0.9906)
			(end -0.3048 0.9906)
			(stroke
				(width 0.1)
				(type default)
			)
			(layer "B.Fab")
		)
		(fp_line
			(start -0.3048 -0.1016)
			(end 0.3048 -0.1016)
			(stroke
				(width 0.1)
				(type default)
			)
			(layer "B.Fab")
		)
		(fp_line
			(start 0.3048 -0.1016)
			(end 0.3048 0.9906)
			(stroke
				(width 0.1)
				(type default)
			)
			(layer "B.Fab")
		)
		(pad "1" smd rect
			(at 0 0 90)
			(size 0.508 0.508)
			(layers "B.Cu" "B.Mask" "B.Paste")
			(net "P3V3_STBY")
		)
		(pad "2" smd rect
			(at 0 0.889 90)
			(size 0.508 0.508)
			(layers "B.Cu" "B.Mask" "B.Paste")
			(net "GND")
		)
		(zone
			(layer "B.Cu")
			(hatch none 0.5)
			(connect_pads
				(clearance 0)
			)
			(min_thickness 0.25)
			(keepout
				(tracks not_allowed)
				(vias allowed)
				(pads allowed)
				(copperpour not_allowed)
				(footprints allowed)
			)
			(placement
				(enabled no)
				(sheetname "")
			)
			(fill
				(thermal_gap 0.5)
				(thermal_bridge_width 0.5)
				(island_removal_mode 0)
			)
			(polygon
				(pts
					(xy 462.314544 -10.95248) (xy 462.314544 -10.44448) (xy 462.695544 -10.44448) (xy 462.695544 -10.95248)
				)
			)
		)
		(zone
			(layer "B.Cu")
			(hatch none 0.5)
			(connect_pads
				(clearance 0)
			)
			(min_thickness 0.25)
			(keepout
				(tracks allowed)
				(vias not_allowed)
				(pads allowed)
				(copperpour not_allowed)
				(footprints allowed)
			)
			(placement
				(enabled no)
				(sheetname "")
			)
			(fill
				(thermal_gap 0.5)
				(thermal_bridge_width 0.5)
				(island_removal_mode 0)
			)
			(polygon
				(pts
					(xy 462.314544 -10.95248) (xy 462.314544 -10.44448) (xy 462.695544 -10.44448) (xy 462.695544 -10.95248)
				)
			)
		)
	)
)
